(kicad_pcb
	(version 20240108)
	(generator "pcbnew")
	(generator_version "8.0")
	(general
		(thickness 1.62)
		(legacy_teardrops no)
	)
	(paper "A4")
	(title_block
		(title "Jetson Orin Baseboard")
		(date "2025-03-12")
		(rev "1.3.4")
		(company "Antmicro Ltd")
		(comment 1 "www.antmicro.com")
		(comment 9 "footprints 269-271 of 677")
	)
	(layers
		(0 "F.Cu" signal)
		(1 "In1.Cu" signal)
		(2 "In2.Cu" signal)
		(3 "In3.Cu" signal)
		(4 "In4.Cu" jumper)
		(5 "In5.Cu" signal)
		(6 "In6.Cu" signal)
		(31 "B.Cu" signal)
		(32 "B.Adhes" user "B.Adhesive")
		(33 "F.Adhes" user "F.Adhesive")
		(34 "B.Paste" user)
		(35 "F.Paste" user)
		(36 "B.SilkS" user "B.Silkscreen")
		(37 "F.SilkS" user "F.Silkscreen")
		(38 "B.Mask" user)
		(39 "F.Mask" user)
		(40 "Dwgs.User" user "User.Drawings")
		(41 "Cmts.User" user "User.Comments")
		(42 "Eco1.User" user "User.Eco1")
		(43 "Eco2.User" user "User.Eco2")
		(44 "Edge.Cuts" user)
		(45 "Margin" user)
		(46 "B.CrtYd" user "B.Courtyard")
		(47 "F.CrtYd" user "F.Courtyard")
		(48 "B.Fab" user)
		(49 "F.Fab" user)
	)
	(footprint "antmicro-footprints:C_0402_1005Metric"
		(layer "F.Cu")
		(at 134.71 92.3 180)
		(descr "Capacitor SMD 0402")
		(tags "capacitor SMD 0402")
		(property "Reference" "C111"
			(at 3.76 -0.5 180)
			(layer "F.SilkS")
			(effects
				(font
					(size 0.7 0.7)
					(thickness 0.15)
				)
				(justify left bottom)
			)
		)
		(property "Value" "C_100n_0402"
			(at 0 1.4 180)
			(layer "F.Fab")
			(effects
				(font
					(size 0.7 0.7)
					(thickness 0.15)
				)
				(justify left bottom)
			)
		)
		(property "Footprint" "antmicro-footprints:C_0402_1005Metric"
			(at 0 0 180)
			(layer "F.Fab")
			(hide yes)
			(effects
				(font
					(size 1.27 1.27)
					(thickness 0.15)
				)
			)
		)
		(property "Datasheet" "https://www.murata.com/products/productdetail?partno=GRM155R61H104KE14%23"
			(at 0 0 180)
			(layer "F.Fab")
			(hide yes)
			(effects
				(font
					(size 1.27 1.27)
					(thickness 0.15)
				)
			)
		)
		(property "Author" "Antmicro"
			(at 269.42 184.6 0)
			(layer "F.Fab")
			(hide yes)
			(effects
				(font
					(size 1 1)
					(thickness 0.15)
				)
			)
		)
		(property "Dielectric" "X5R"
			(at 269.42 184.6 0)
			(layer "F.Fab")
			(hide yes)
			(effects
				(font
					(size 1 1)
					(thickness 0.15)
				)
			)
		)
		(property "License" "Apache-2.0"
			(at 269.42 184.6 0)
			(layer "F.Fab")
			(hide yes)
			(effects
				(font
					(size 1 1)
					(thickness 0.15)
				)
			)
		)
		(property "MPN" "GRM155R61H104KE14D"
			(at 269.42 184.6 0)
			(layer "F.Fab")
			(hide yes)
			(effects
				(font
					(size 1 1)
					(thickness 0.15)
				)
			)
		)
		(property "Manufacturer" "Murata"
			(at 269.42 184.6 0)
			(layer "F.Fab")
			(hide yes)
			(effects
				(font
					(size 1 1)
					(thickness 0.15)
				)
			)
		)
		(property "Val" "100n"
			(at 269.42 184.6 0)
			(layer "F.Fab")
			(hide yes)
			(effects
				(font
					(size 1 1)
					(thickness 0.15)
				)
			)
		)
		(property "Voltage" "50V"
			(at 269.42 184.6 0)
			(layer "F.Fab")
			(hide yes)
			(effects
				(font
					(size 1 1)
					(thickness 0.15)
				)
			)
		)
		(sheetname "Peripherals")
		(sheetfile "peripherals.kicad_sch")
		(attr smd)
		(fp_rect
			(start -0.925 -0.47)
			(end 0.925 0.47)
			(stroke
				(width 0.05)
				(type default)
			)
			(fill none)
			(layer "F.CrtYd")
		)
		(fp_line
			(start 0.504 0.248)
			(end -0.494 0.248)
			(stroke
				(width 0.15)
				(type solid)
			)
			(layer "F.Fab")
		)
		(fp_line
			(start 0.504 -0.25)
			(end 0.504 0.248)
			(stroke
				(width 0.15)
				(type solid)
			)
			(layer "F.Fab")
		)
		(fp_line
			(start -0.494 0.248)
			(end -0.494 -0.25)
			(stroke
				(width 0.15)
				(type solid)
			)
			(layer "F.Fab")
		)
		(fp_line
			(start -0.494 -0.25)
			(end 0.504 -0.25)
			(stroke
				(width 0.15)
				(type solid)
			)
			(layer "F.Fab")
		)
		(fp_text user "License: Apache-2.0"
			(at -0.932 5.17 180)
			(layer "F.Fab")
			(hide yes)
			(effects
				(font
					(size 0.7 0.7)
					(thickness 0.15)
				)
				(justify left bottom)
			)
		)
		(fp_text user "${REFERENCE}"
			(at -0.932 3.168 180)
			(layer "F.Fab")
			(hide yes)
			(effects
				(font
					(size 0.7 0.7)
					(thickness 0.15)
				)
				(justify left bottom)
			)
		)
		(fp_text user "Author: Antmicro"
			(at -0.932 4.17 180)
			(layer "F.Fab")
			(hide yes)
			(effects
				(font
					(size 0.7 0.7)
					(thickness 0.15)
				)
				(justify left bottom)
			)
		)
		(pad "1" smd roundrect
			(at -0.48 0 180)
			(size 0.59 0.64)
			(layers "F.Cu" "F.Paste" "F.Mask")
			(roundrect_rratio 0.25)
			(net 414 "/Peripherals/USBSS2_TX_CONN_P")
			(pintype "passive")
		)
		(pad "2" smd roundrect
			(at 0.48 0 180)
			(size 0.59 0.64)
			(layers "F.Cu" "F.Paste" "F.Mask")
			(roundrect_rratio 0.25)
			(net 157 "USBSS1_TX_P")
			(pintype "passive")
		)
	)
	(footprint "antmicro-footprints:C_0603_1608Metric_EIA"
		(layer "F.Cu")
		(at 69.925 91.67 -90)
		(descr "Capacitor SMD 0603, IPC-7351 Density Level A")
		(tags "Capacitor 0603")
		(property "Reference" "C127"
			(at -6.406396 -14.62 -90)
			(layer "F.SilkS")
			(effects
				(font
					(size 0.7 0.7)
					(thickness 0.15)
				)
				(justify left bottom)
			)
		)
		(property "Value" "C_22u_16V_0603"
			(at -1.42757 1.770288 -90)
			(layer "F.Fab")
			(effects
				(font
					(size 0.7 0.7)
					(thickness 0.15)
				)
				(justify left bottom)
			)
		)
		(property "Footprint" "antmicro-footprints:C_0603_1608Metric_EIA"
			(at 0 0 -90)
			(layer "F.Fab")
			(hide yes)
			(effects
				(font
					(size 1.27 1.27)
					(thickness 0.15)
				)
			)
		)
		(property "Datasheet" "https://product.samsungsem.com/mlcc/CL10A226MO7JZN.do"
			(at 0 0 -90)
			(layer "F.Fab")
			(hide yes)
			(effects
				(font
					(size 1.27 1.27)
					(thickness 0.15)
				)
			)
		)
		(property "Description" "SMD Multilayer Ceramic Capacitor"
			(at 0 0 -90)
			(layer "F.Fab")
			(hide yes)
			(effects
				(font
					(size 1.27 1.27)
					(thickness 0.15)
				)
			)
		)
		(property "Manufacturer" "Samsung Electro-Mechanics"
			(at 0 0 -90)
			(unlocked yes)
			(layer "F.Fab")
			(hide yes)
			(effects
				(font
					(size 1 1)
					(thickness 0.15)
				)
			)
		)
		(property "MPN" "CL10A226MO7JZNC"
			(at 0 0 -90)
			(unlocked yes)
			(layer "F.Fab")
			(hide yes)
			(effects
				(font
					(size 1 1)
					(thickness 0.15)
				)
			)
		)
		(property "Val" "22u"
			(at 0 0 -90)
			(unlocked yes)
			(layer "F.Fab")
			(hide yes)
			(effects
				(font
					(size 1 1)
					(thickness 0.15)
				)
			)
		)
		(property "License" "Apache-2.0"
			(at 0 0 -90)
			(unlocked yes)
			(layer "F.Fab")
			(hide yes)
			(effects
				(font
					(size 1 1)
					(thickness 0.15)
				)
			)
		)
		(property "Author" "Antmicro"
			(at 0 0 -90)
			(unlocked yes)
			(layer "F.Fab")
			(hide yes)
			(effects
				(font
					(size 1 1)
					(thickness 0.15)
				)
			)
		)
		(property "Voltage" "16V"
			(at 0 0 -90)
			(unlocked yes)
			(layer "F.Fab")
			(hide yes)
			(effects
				(font
					(size 1 1)
					(thickness 0.15)
				)
			)
		)
		(property "Dielectric" ""
			(at 0 0 -90)
			(unlocked yes)
			(layer "F.Fab")
			(hide yes)
			(effects
				(font
					(size 1 1)
					(thickness 0.15)
				)
			)
		)
		(sheetname "Supply")
		(sheetfile "supply.kicad_sch")
		(attr smd)
		(fp_line
			(start -0.15 0.55)
			(end 0.15 0.55)
			(stroke
				(width 0.15)
				(type solid)
			)
			(layer "F.SilkS")
		)
		(fp_line
			(start -0.15 -0.55)
			(end 0.15 -0.55)
			(stroke
				(width 0.15)
				(type solid)
			)
			(layer "F.SilkS")
		)
		(fp_rect
			(start -1.25 -0.65)
			(end 1.25 0.65)
			(stroke
				(width 0.05)
				(type solid)
			)
			(fill none)
			(layer "F.CrtYd")
		)
		(fp_rect
			(start -0.8 -0.45)
			(end 0.8 0.45)
			(stroke
				(width 0.15)
				(type solid)
			)
			(fill none)
			(layer "F.Fab")
		)
		(fp_text user "License: Apache-2.0"
			(at -1.682 5.895 -90)
			(layer "F.Fab")
			(hide yes)
			(effects
				(font
					(size 0.7 0.7)
					(thickness 0.15)
				)
				(justify left bottom)
			)
		)
		(fp_text user "${REFERENCE}"
			(at -1.682 3.895 -90)
			(layer "F.Fab")
			(hide yes)
			(effects
				(font
					(size 0.7 0.7)
					(thickness 0.15)
				)
				(justify left bottom)
			)
		)
		(fp_text user "Author: Antmicro"
			(at -1.682 4.894 -90)
			(layer "F.Fab")
			(hide yes)
			(effects
				(font
					(size 0.7 0.7)
					(thickness 0.15)
				)
				(justify left bottom)
			)
		)
		(pad "1" smd roundrect
			(at -0.7 0 270)
			(size 0.8 1.1)
			(layers "F.Cu" "F.Paste" "F.Mask")
			(roundrect_rratio 0.2)
			(net 1 "GND")
			(pintype "passive")
		)
		(pad "2" smd roundrect
			(at 0.7 0 270)
			(size 0.8 1.1)
			(layers "F.Cu" "F.Paste" "F.Mask")
			(roundrect_rratio 0.2)
			(net 641 "/Supply/3V3_OUT")
			(pintype "passive")
		)
	)
	(footprint "antmicro-footprints:C_0402_1005Metric"
		(layer "F.Cu")
		(at 127.05 95.2 180)
		(descr "Capacitor SMD 0402")
		(tags "capacitor SMD 0402")
		(property "Reference" "C10"
			(at 1 -1.3 180)
			(layer "F.SilkS")
			(effects
				(font
					(size 0.7 0.7)
					(thickness 0.15)
				)
				(justify left bottom)
			)
		)
		(property "Value" "C_220n_0402"
			(at 0 1.4 180)
			(layer "F.Fab")
			(effects
				(font
					(size 0.7 0.7)
					(thickness 0.15)
				)
				(justify left bottom)
			)
		)
		(property "Footprint" "antmicro-footprints:C_0402_1005Metric"
			(at 0 0 180)
			(layer "F.Fab")
			(hide yes)
			(effects
				(font
					(size 1.27 1.27)
					(thickness 0.15)
				)
			)
		)
		(property "Datasheet" "https://www.yageo.com/en/Chart/Download/pdf/CC0402KRX5R6BB224"
			(at 0 0 180)
			(layer "F.Fab")
			(hide yes)
			(effects
				(font
					(size 1.27 1.27)
					(thickness 0.15)
				)
			)
		)
		(property "Author" "Antmicro"
			(at 254.1 190.4 0)
			(layer "F.Fab")
			(hide yes)
			(effects
				(font
					(size 1 1)
					(thickness 0.15)
				)
			)
		)
		(property "Dielectric" ""
			(at 254.1 190.4 0)
			(layer "F.Fab")
			(hide yes)
			(effects
				(font
					(size 1 1)
					(thickness 0.15)
				)
			)
		)
		(property "License" "Apache-2.0"
			(at 254.1 190.4 0)
			(layer "F.Fab")
			(hide yes)
			(effects
				(font
					(size 1 1)
					(thickness 0.15)
				)
			)
		)
		(property "MPN" "CC0402KRX5R6BB224"
			(at 254.1 190.4 0)
			(layer "F.Fab")
			(hide yes)
			(effects
				(font
					(size 1 1)
					(thickness 0.15)
				)
			)
		)
		(property "Manufacturer" "YAGEO"
			(at 254.1 190.4 0)
			(layer "F.Fab")
			(hide yes)
			(effects
				(font
					(size 1 1)
					(thickness 0.15)
				)
			)
		)
		(property "Val" "220n"
			(at 254.1 190.4 0)
			(layer "F.Fab")
			(hide yes)
			(effects
				(font
					(size 1 1)
					(thickness 0.15)
				)
			)
		)
		(property "Voltage" ""
			(at 254.1 190.4 0)
			(layer "F.Fab")
			(hide yes)
			(effects
				(font
					(size 1 1)
					(thickness 0.15)
				)
			)
		)
		(sheetname "M.2")
		(sheetfile "m-2.kicad_sch")
		(attr smd)
		(fp_rect
			(start -0.925 -0.47)
			(end 0.925 0.47)
			(stroke
				(width 0.05)
				(type default)
			)
			(fill none)
			(layer "F.CrtYd")
		)
		(fp_line
			(start 0.504 0.248)
			(end -0.494 0.248)
			(stroke
				(width 0.15)
				(type solid)
			)
			(layer "F.Fab")
		)
		(fp_line
			(start 0.504 -0.25)
			(end 0.504 0.248)
			(stroke
				(width 0.15)
				(type solid)
			)
			(layer "F.Fab")
		)
		(fp_line
			(start -0.494 0.248)
			(end -0.494 -0.25)
			(stroke
				(width 0.15)
				(type solid)
			)
			(layer "F.Fab")
		)
		(fp_line
			(start -0.494 -0.25)
			(end 0.504 -0.25)
			(stroke
				(width 0.15)
				(type solid)
			)
			(layer "F.Fab")
		)
		(fp_text user "Author: Antmicro"
			(at -0.932 4.17 180)
			(layer "F.Fab")
			(hide yes)
			(effects
				(font
					(size 0.7 0.7)
					(thickness 0.15)
				)
				(justify left bottom)
			)
		)
		(fp_text user "License: Apache-2.0"
			(at -0.932 5.17 180)
			(layer "F.Fab")
			(hide yes)
			(effects
				(font
					(size 0.7 0.7)
					(thickness 0.15)
				)
				(justify left bottom)
			)
		)
		(fp_text user "${REFERENCE}"
			(at -0.932 3.168 180)
			(layer "F.Fab")
			(hide yes)
			(effects
				(font
					(size 0.7 0.7)
					(thickness 0.15)
				)
				(justify left bottom)
			)
		)
		(pad "1" smd roundrect
			(at -0.48 0 180)
			(size 0.59 0.64)
			(layers "F.Cu" "F.Paste" "F.Mask")
			(roundrect_rratio 0.25)
			(net 450 "PCIE1_TX0_N")
			(pintype "passive")
		)
		(pad "2" smd roundrect
			(at 0.48 0 180)
			(size 0.59 0.64)
			(layers "F.Cu" "F.Paste" "F.Mask")
			(roundrect_rratio 0.25)
			(net 97 "/M.2/C_PCIE1_TX0_N")
			(pintype "passive")
		)
	)
)
